(kicad_pcb
	(version 20260206)
	(generator "pcbnew")
	(generator_version "10.0")
	(general
		(thickness 0.77098)
		(legacy_teardrops no)
	)
	(paper "A4")
	(title_block
		(title "gnss-m2-zed-f9t — M2_ZED-F9T_MODULE.PcbDoc")
		(comment 1 "Time Appliance Project (Time Card) / footprints 23-27 of 36")
	)
	(layers
		(0 "F.Cu" signal "L01-Top Layer")
		(4 "In1.Cu" signal "L02-Inner Layer")
		(6 "In2.Cu" signal "L03-Inner Layer")
		(2 "B.Cu" signal "L04-Bottom Layer")
		(9 "F.Adhes" user "F.Adhesive")
		(11 "B.Adhes" user "B.Adhesive")
		(13 "F.Paste" user "Top Paste")
		(15 "B.Paste" user "Bottom Paste")
		(5 "F.SilkS" user "Top Overlay")
		(7 "B.SilkS" user "Bottom Overlay")
		(1 "F.Mask" user "Top Solder")
		(3 "B.Mask" user "Bottom Solder")
		(17 "Dwgs.User" user "User.Drawings")
		(19 "Cmts.User" user "User.Comments")
		(21 "Eco1.User" user "User.Eco1")
		(23 "Eco2.User" user "User.Eco2")
		(25 "Edge.Cuts" user)
		(27 "Margin" user)
		(31 "F.CrtYd" user "Top Courtyard")
		(29 "B.CrtYd" user "Bottom Courtyard")
		(35 "F.Fab" user "Top Component Outline")
		(33 "B.Fab" user "Bottom Component Outline 2")
	)
	(footprint "Vault:FP-LTST-C191KGKT-MFG"
		(layer "F.Cu")
		(at 140.038955 114.27079)
		(property "Reference" "D3"
			(at -0.03785 1.333831 0)
			(unlocked yes)
			(layer "F.SilkS")
			(effects
				(font
					(face "Arial")
					(size 0.96012 0.96012)
					(thickness 0.254)
				)
			)
		)
		(property "Value" "LTST-C191KGKT"
			(at 7.705855 2.207911 0)
			(unlocked yes)
			(layer "F.SilkS")
			(hide yes)
			(effects
				(font
					(face "Arial")
					(size 0.96012 0.96012)
					(thickness 0.254)
				)
			)
		)
		(sheetname "01-M2_ZED-F9T_MODULE")
		(sheetfile "01-M2_ZED-F9T_MODULE.kicad_sch")
		(duplicate_pad_numbers_are_jumpers no)
		(fp_line
			(start -0.85001 -0.775)
			(end 0.85 -0.775)
			(stroke
				(width 0.2)
				(type solid)
			)
			(layer "F.SilkS")
		)
		(fp_line
			(start -0.85001 0.775)
			(end 0.85 0.775)
			(stroke
				(width 0.2)
				(type solid)
			)
			(layer "F.SilkS")
		)
		(fp_circle
			(center -1.7 0)
			(end -1.7 -0.125)
			(stroke
				(width 0.25)
				(type solid)
			)
			(fill no)
			(layer "F.SilkS")
		)
		(fp_line
			(start -1.25 -0.55)
			(end 1.25 -0.55)
			(stroke
				(width 0.2)
				(type solid)
			)
			(layer "F.CrtYd")
		)
		(fp_line
			(start -1.25 0.55)
			(end -1.25 -0.55)
			(stroke
				(width 0.2)
				(type solid)
			)
			(layer "F.CrtYd")
		)
		(fp_line
			(start -1.25 0.55)
			(end 1.25 0.55)
			(stroke
				(width 0.2)
				(type solid)
			)
			(layer "F.CrtYd")
		)
		(fp_line
			(start 1.25 0.55)
			(end 1.25 -0.55)
			(stroke
				(width 0.2)
				(type solid)
			)
			(layer "F.CrtYd")
		)
		(fp_line
			(start -1.25 -0.55)
			(end 1.25 -0.55)
			(stroke
				(width 0.2)
				(type solid)
			)
			(layer "F.Fab")
		)
		(fp_line
			(start -1.25 0.55)
			(end -1.25 -0.55)
			(stroke
				(width 0.2)
				(type solid)
			)
			(layer "F.Fab")
		)
		(fp_line
			(start -1.25 0.55)
			(end 1.25 0.55)
			(stroke
				(width 0.2)
				(type solid)
			)
			(layer "F.Fab")
		)
		(fp_line
			(start -0.5 0)
			(end 0.49999 0)
			(stroke
				(width 0.1)
				(type solid)
			)
			(layer "F.Fab")
		)
		(fp_line
			(start 0 0.5)
			(end 0 -0.5)
			(stroke
				(width 0.1)
				(type solid)
			)
			(layer "F.Fab")
		)
		(fp_line
			(start 1.25 0.55)
			(end 1.25 -0.55)
			(stroke
				(width 0.2)
				(type solid)
			)
			(layer "F.Fab")
		)
		(fp_text user "${REFERENCE}"
			(at 0 0.28425 360)
			(unlocked yes)
			(layer "F.Fab")
			(effects
				(font
					(face "Arial")
					(size 0.63 0.63)
					(thickness 0.1)
				)
				(justify left bottom)
			)
		)
		(pad "1" smd rect
			(at -0.75001 0)
			(size 0.8 0.8)
			(layers "F.Cu" "F.Mask" "F.Paste")
			(net "NetD3_1")
			(solder_mask_margin 0)
			(solder_paste_margin 0)
		)
		(pad "2" smd rect
			(at 0.75 0)
			(size 0.8 0.8)
			(layers "F.Cu" "F.Mask" "F.Paste")
			(net "+3V3")
			(solder_mask_margin 0)
			(solder_paste_margin 0)
		)
	)
	(footprint "Vault:FP-CL542-IPC_C"
		(layer "F.Cu")
		(at 143.901105 113.3036)
		(property "Reference" "C5"
			(at -1.3 -0.455485 0)
			(unlocked yes)
			(layer "F.SilkS")
			(effects
				(font
					(face "Arial")
					(size 0.40005 0.40005)
					(thickness 0.1778)
				)
			)
		)
		(property "Value" "1uF_25V_0402"
			(at 4.88765 1.959815 0)
			(unlocked yes)
			(layer "F.SilkS")
			(hide yes)
			(effects
				(font
					(face "Arial")
					(size 0.40005 0.40005)
					(thickness 0.1778)
				)
			)
		)
		(sheetname "01-M2_ZED-F9T_MODULE")
		(sheetfile "01-M2_ZED-F9T_MODULE.kicad_sch")
		(duplicate_pad_numbers_are_jumpers no)
		(fp_line
			(start -0.63624 -0.675)
			(end 0.63624 -0.675)
			(stroke
				(width 0.2)
				(type solid)
			)
			(layer "F.SilkS")
		)
		(fp_line
			(start -0.63624 0.675)
			(end 0.63624 0.675)
			(stroke
				(width 0.2)
				(type solid)
			)
			(layer "F.SilkS")
		)
		(fp_line
			(start -0.73624 -0.375)
			(end 0.73624 -0.375)
			(stroke
				(width 0.2)
				(type solid)
			)
			(layer "F.CrtYd")
		)
		(fp_line
			(start -0.73624 0.375)
			(end -0.73624 -0.375)
			(stroke
				(width 0.2)
				(type solid)
			)
			(layer "F.CrtYd")
		)
		(fp_line
			(start -0.73624 0.375)
			(end 0.73624 0.375)
			(stroke
				(width 0.2)
				(type solid)
			)
			(layer "F.CrtYd")
		)
		(fp_line
			(start 0.73624 0.375)
			(end 0.73624 -0.375)
			(stroke
				(width 0.2)
				(type solid)
			)
			(layer "F.CrtYd")
		)
		(fp_line
			(start -0.73624 -0.375)
			(end 0.73624 -0.375)
			(stroke
				(width 0.2)
				(type solid)
			)
			(layer "F.Fab")
		)
		(fp_line
			(start -0.73624 0.375)
			(end -0.73624 -0.375)
			(stroke
				(width 0.2)
				(type solid)
			)
			(layer "F.Fab")
		)
		(fp_line
			(start -0.73624 0.375)
			(end 0.73624 0.375)
			(stroke
				(width 0.2)
				(type solid)
			)
			(layer "F.Fab")
		)
		(fp_line
			(start -0.5 0)
			(end 0.5 0)
			(stroke
				(width 0.1)
				(type solid)
			)
			(layer "F.Fab")
		)
		(fp_line
			(start -0.5 0)
			(end 0.5 0)
			(stroke
				(width 0.1)
				(type solid)
			)
			(layer "F.Fab")
		)
		(fp_line
			(start 0 0.5)
			(end 0 -0.5)
			(stroke
				(width 0.1)
				(type solid)
			)
			(layer "F.Fab")
		)
		(fp_line
			(start 0 0.5)
			(end 0 -0.5)
			(stroke
				(width 0.1)
				(type solid)
			)
			(layer "F.Fab")
		)
		(fp_line
			(start 0.73624 0.375)
			(end 0.73624 -0.375)
			(stroke
				(width 0.2)
				(type solid)
			)
			(layer "F.Fab")
		)
		(fp_text user "${REFERENCE}"
			(at 0 0.28425 360)
			(unlocked yes)
			(layer "F.Fab")
			(effects
				(font
					(face "Arial")
					(size 0.63 0.63)
					(thickness 0.1)
				)
				(justify left bottom)
			)
		)
		(pad "1" smd rect
			(at -0.37856 0)
			(size 0.51535 0.47247)
			(layers "F.Cu" "F.Mask" "F.Paste")
			(net "GND")
			(solder_mask_margin 0)
			(solder_paste_margin 0)
		)
		(pad "2" smd rect
			(at 0.37856 0)
			(size 0.51535 0.47247)
			(layers "F.Cu" "F.Mask" "F.Paste")
			(net "NetC5_2")
			(solder_mask_margin 0)
			(solder_paste_margin 0)
		)
	)
	(footprint "Vault:FP-GRM31C-0_2-e0_3_0_8-IPC_C"
		(layer "F.Cu")
		(at 157.701105 119.6036 90)
		(property "Reference" "C6"
			(at 2.596754 0.6 0)
			(unlocked yes)
			(layer "F.SilkS")
			(effects
				(font
					(face "Arial")
					(size 0.48006 0.48006)
					(thickness 0.254)
				)
			)
		)
		(property "Value" "47uF_6.3V_1206"
			(at 8.366015 2.430251 90)
			(unlocked yes)
			(layer "F.SilkS")
			(hide yes)
			(effects
				(font
					(face "Arial")
					(size 0.96012 0.96012)
					(thickness 0.254)
				)
			)
		)
		(sheetname "03-M2_GoldFingers")
		(sheetfile "03-M2_GoldFingers.kicad_sch")
		(duplicate_pad_numbers_are_jumpers no)
		(fp_line
			(start -0.39847 -0.9)
			(end 0.39846 -0.9)
			(stroke
				(width 0.2)
				(type solid)
			)
			(layer "F.SilkS")
		)
		(fp_line
			(start -0.39847 0.9)
			(end 0.39846 0.9)
			(stroke
				(width 0.2)
				(type solid)
			)
			(layer "F.SilkS")
		)
		(fp_line
			(start 1.9531 -1)
			(end 1.9531 1)
			(stroke
				(width 0.2)
				(type solid)
			)
			(layer "F.CrtYd")
		)
		(fp_line
			(start -1.9531 -1)
			(end 1.9531 -1)
			(stroke
				(width 0.2)
				(type solid)
			)
			(layer "F.CrtYd")
		)
		(fp_line
			(start -1.9531 -1)
			(end -1.9531 1)
			(stroke
				(width 0.2)
				(type solid)
			)
			(layer "F.CrtYd")
		)
		(fp_line
			(start -1.9531 1)
			(end 1.9531 1)
			(stroke
				(width 0.2)
				(type solid)
			)
			(layer "F.CrtYd")
		)
		(fp_line
			(start 1.9531 -1)
			(end 1.9531 1)
			(stroke
				(width 0.2)
				(type solid)
			)
			(layer "F.Fab")
		)
		(fp_line
			(start -1.9531 -1)
			(end 1.9531 -1)
			(stroke
				(width 0.2)
				(type solid)
			)
			(layer "F.Fab")
		)
		(fp_line
			(start -1.9531 -1)
			(end -1.9531 1)
			(stroke
				(width 0.2)
				(type solid)
			)
			(layer "F.Fab")
		)
		(fp_line
			(start 0 -0.5)
			(end 0 0.5)
			(stroke
				(width 0.1)
				(type solid)
			)
			(layer "F.Fab")
		)
		(fp_line
			(start -0.5 0)
			(end 0.5 0)
			(stroke
				(width 0.1)
				(type solid)
			)
			(layer "F.Fab")
		)
		(fp_line
			(start -1.9531 1)
			(end 1.9531 1)
			(stroke
				(width 0.2)
				(type solid)
			)
			(layer "F.Fab")
		)
		(fp_text user "${REFERENCE}"
			(at -0.00002 0.09602 90)
			(unlocked yes)
			(layer "F.Fab")
			(effects
				(font
					(face "Arial")
					(size 0.63 0.63)
					(thickness 0.1)
				)
				(justify left bottom)
			)
		)
		(pad "1" smd rect
			(at -1.27578 0 90)
			(size 1.15464 1.7062)
			(layers "F.Cu" "F.Mask" "F.Paste")
			(net "+3V3")
			(solder_mask_margin 0)
			(solder_paste_margin 0)
		)
		(pad "2" smd rect
			(at 1.27578 0 90)
			(size 1.15464 1.7062)
			(layers "F.Cu" "F.Mask" "F.Paste")
			(net "GND")
			(solder_mask_margin 0)
			(solder_paste_margin 0)
		)
	)
	(footprint "Vault:FP-CL542-IPC_C"
		(layer "F.Cu")
		(at 150.701105 110.5036)
		(property "Reference" "C3"
			(at 1.302655 -0.080485 0)
			(unlocked yes)
			(layer "F.SilkS")
			(effects
				(font
					(face "Arial")
					(size 0.40005 0.40005)
					(thickness 0.1778)
				)
			)
		)
		(property "Value" "1uF_25V_0402"
			(at 4.88765 1.959815 0)
			(unlocked yes)
			(layer "F.SilkS")
			(hide yes)
			(effects
				(font
					(face "Arial")
					(size 0.40005 0.40005)
					(thickness 0.1778)
				)
			)
		)
		(sheetname "01-M2_ZED-F9T_MODULE")
		(sheetfile "01-M2_ZED-F9T_MODULE.kicad_sch")
		(duplicate_pad_numbers_are_jumpers no)
		(fp_line
			(start -0.73624 -0.375)
			(end 0.73624 -0.375)
			(stroke
				(width 0.2)
				(type solid)
			)
			(layer "F.CrtYd")
		)
		(fp_line
			(start -0.73624 0.375)
			(end -0.73624 -0.375)
			(stroke
				(width 0.2)
				(type solid)
			)
			(layer "F.CrtYd")
		)
		(fp_line
			(start -0.73624 0.375)
			(end 0.73624 0.375)
			(stroke
				(width 0.2)
				(type solid)
			)
			(layer "F.CrtYd")
		)
		(fp_line
			(start 0.73624 0.375)
			(end 0.73624 -0.375)
			(stroke
				(width 0.2)
				(type solid)
			)
			(layer "F.CrtYd")
		)
		(fp_line
			(start -0.73624 -0.375)
			(end 0.73624 -0.375)
			(stroke
				(width 0.2)
				(type solid)
			)
			(layer "F.Fab")
		)
		(fp_line
			(start -0.73624 0.375)
			(end -0.73624 -0.375)
			(stroke
				(width 0.2)
				(type solid)
			)
			(layer "F.Fab")
		)
		(fp_line
			(start -0.73624 0.375)
			(end 0.73624 0.375)
			(stroke
				(width 0.2)
				(type solid)
			)
			(layer "F.Fab")
		)
		(fp_line
			(start -0.5 0)
			(end 0.5 0)
			(stroke
				(width 0.1)
				(type solid)
			)
			(layer "F.Fab")
		)
		(fp_line
			(start -0.5 0)
			(end 0.5 0)
			(stroke
				(width 0.1)
				(type solid)
			)
			(layer "F.Fab")
		)
		(fp_line
			(start 0 0.5)
			(end 0 -0.5)
			(stroke
				(width 0.1)
				(type solid)
			)
			(layer "F.Fab")
		)
		(fp_line
			(start 0 0.5)
			(end 0 -0.5)
			(stroke
				(width 0.1)
				(type solid)
			)
			(layer "F.Fab")
		)
		(fp_line
			(start 0.73624 0.375)
			(end 0.73624 -0.375)
			(stroke
				(width 0.2)
				(type solid)
			)
			(layer "F.Fab")
		)
		(fp_text user "${REFERENCE}"
			(at 0 0.28425 360)
			(unlocked yes)
			(layer "F.Fab")
			(effects
				(font
					(face "Arial")
					(size 0.63 0.63)
					(thickness 0.1)
				)
				(justify left bottom)
			)
		)
		(pad "1" smd rect
			(at -0.37856 0)
			(size 0.51535 0.47247)
			(layers "F.Cu" "F.Mask" "F.Paste")
			(net "+3V3")
			(solder_mask_margin 0)
			(solder_paste_margin 0)
		)
		(pad "2" smd rect
			(at 0.37856 0)
			(size 0.51535 0.47247)
			(layers "F.Cu" "F.Mask" "F.Paste")
			(net "GND")
			(solder_mask_margin 0)
			(solder_paste_margin 0)
		)
	)
	(footprint "Vault:DCU0008A_N"
		(layer "F.Cu")
		(at 139.601105 88.4036 -90)
		(property "Reference" "U3"
			(at -0.000005 1.798979 90)
			(unlocked yes)
			(layer "F.SilkS")
			(effects
				(font
					(face "Arial")
					(size 0.96012 0.96012)
					(thickness 0.254)
				)
			)
		)
		(property "Value" "SN74LVC3G07DCUR"
			(at 9.17849 2.665111 270)
			(unlocked yes)
			(layer "F.SilkS")
			(hide yes)
			(effects
				(font
					(face "Arial")
					(size 0.96012 0.96012)
					(thickness 0.254)
				)
			)
		)
		(sheetname "02-Antenna_Supervisor")
		(sheetfile "02-Antenna_Supervisor.kicad_sch")
		(duplicate_pad_numbers_are_jumpers no)
		(fp_line
			(start -0.8 1.05)
			(end -0.8 -1.05)
			(stroke
				(width 0.2)
				(type solid)
			)
			(layer "F.SilkS")
		)
		(fp_line
			(start 0.8 1.05)
			(end -0.8 1.05)
			(stroke
				(width 0.2)
				(type solid)
			)
			(layer "F.SilkS")
		)
		(fp_line
			(start 0.8 1.05)
			(end 0.8 -1.05)
			(stroke
				(width 0.2)
				(type solid)
			)
			(layer "F.SilkS")
		)
		(fp_line
			(start 0.8 -1.05)
			(end -0.8 -1.05)
			(stroke
				(width 0.2)
				(type solid)
			)
			(layer "F.SilkS")
		)
		(fp_circle
			(center -1.6 -1.45)
			(end -1.725 -1.45)
			(stroke
				(width 0.25)
				(type solid)
			)
			(fill no)
			(layer "F.SilkS")
		)
		(fp_line
			(start -2.225 1.3)
			(end -2.225 -1.3)
			(stroke
				(width 0.05)
				(type solid)
			)
			(layer "F.CrtYd")
		)
		(fp_line
			(start 2.225 1.3)
			(end -2.225 1.3)
			(stroke
				(width 0.05)
				(type solid)
			)
			(layer "F.CrtYd")
		)
		(fp_line
			(start 2.225 1.3)
			(end 2.225 -1.3)
			(stroke
				(width 0.05)
				(type solid)
			)
			(layer "F.CrtYd")
		)
		(fp_line
			(start 0 0.5)
			(end 0 -0.5)
			(stroke
				(width 0.1)
				(type solid)
			)
			(layer "F.CrtYd")
		)
		(fp_line
			(start 0.5 0)
			(end -0.5 0)
			(stroke
				(width 0.1)
				(type solid)
			)
			(layer "F.CrtYd")
		)
		(fp_line
			(start 2.225 -1.3)
			(end -2.225 -1.3)
			(stroke
				(width 0.05)
				(type solid)
			)
			(layer "F.CrtYd")
		)
		(pad "1" smd roundrect
			(at -1.6 -0.75)
			(size 0.3 0.8)
			(layers "F.Cu" "F.Mask" "F.Paste")
			(roundrect_rratio 0.165)
			(net "NetU3_1")
		)
		(pad "2" smd roundrect
			(at -1.6 -0.25)
			(size 0.3 0.8)
			(layers "F.Cu" "F.Mask" "F.Paste")
			(roundrect_rratio 0.165)
			(net "NetQ1_1")
		)
		(pad "3" smd roundrect
			(at -1.6 0.25)
			(size 0.3 0.8)
			(layers "F.Cu" "F.Mask" "F.Paste")
			(roundrect_rratio 0.165)
			(net "NetC12_1")
		)
		(pad "4" smd roundrect
			(at -1.6 0.75)
			(size 0.3 0.8)
			(layers "F.Cu" "F.Mask" "F.Paste")
			(roundrect_rratio 0.165)
			(net "GND")
		)
		(pad "5" smd roundrect
			(at 1.6 0.75)
			(size 0.3 0.8)
			(layers "F.Cu" "F.Mask" "F.Paste")
			(roundrect_rratio 0.165)
			(net "ANT_SHORT_N")
		)
		(pad "6" smd roundrect
			(at 1.6 0.25)
			(size 0.3 0.8)
			(layers "F.Cu" "F.Mask" "F.Paste")
			(roundrect_rratio 0.165)
			(net "ANT_OFF")
		)
		(pad "7" smd roundrect
			(at 1.6 -0.25)
			(size 0.3 0.8)
			(layers "F.Cu" "F.Mask" "F.Paste")
			(roundrect_rratio 0.165)
			(net "ANT_DET")
		)
		(pad "8" smd roundrect
			(at 1.6 -0.75)
			(size 0.3 0.8)
			(layers "F.Cu" "F.Mask" "F.Paste")
			(roundrect_rratio 0.165)
			(net "+3V3")
		)
	)
)
